(kicad_pcb
	(version 20241229)
	(generator "pcbnew")
	(generator_version "9.0")
	(general
		(thickness 1.599998)
		(legacy_teardrops no)
	)
	(paper "A4")
	(title_block
		(title "Artix - Datacenter Secure Control Module (DC-SCM)")
		(date "2024-11-06")
		(rev "1.1.3")
		(comment 9 "footprints 16-20 of 544")
	)
	(layers
		(0 "F.Cu" signal)
		(4 "In1.Cu" signal)
		(6 "In2.Cu" signal)
		(8 "In3.Cu" signal)
		(10 "In4.Cu" signal)
		(12 "In5.Cu" signal)
		(14 "In6.Cu" signal)
		(2 "B.Cu" signal)
		(9 "F.Adhes" user "F.Adhesive")
		(11 "B.Adhes" user "B.Adhesive")
		(13 "F.Paste" user)
		(15 "B.Paste" user)
		(5 "F.SilkS" user "F.Silkscreen")
		(7 "B.SilkS" user "B.Silkscreen")
		(1 "F.Mask" user)
		(3 "B.Mask" user)
		(17 "Dwgs.User" user "User.Drawings")
		(19 "Cmts.User" user "User.Comments")
		(21 "Eco1.User" user "User.Eco1")
		(23 "Eco2.User" user "User.Eco2")
		(25 "Edge.Cuts" user)
		(27 "Margin" user)
		(31 "F.CrtYd" user "F.Courtyard")
		(29 "B.CrtYd" user "B.Courtyard")
		(35 "F.Fab" user)
		(33 "B.Fab" user)
	)
	(footprint "antmicro-footprints:C_0402_1005Metric"
		(layer "F.Cu")
		(at 108 144.6 -90)
		(descr "Capacitor SMD 0402")
		(tags "capacitor SMD 0402")
		(property "Reference" "C44"
			(at -3 -0.4 90)
			(layer "F.SilkS")
			(effects
				(font
					(size 0.7 0.7)
					(thickness 0.15)
				)
				(justify right bottom)
			)
		)
		(property "Value" "C_100n_6V3_0402"
			(at 0 1.4 90)
			(layer "F.Fab")
			(effects
				(font
					(size 0.7 0.7)
					(thickness 0.15)
				)
				(justify right bottom)
			)
		)
		(property "Datasheet" "https://www.passivecomponent.com/wp-content/uploads/datasheet/WTC_MLCC_General_Purpose.pdf"
			(at 0 0 270)
			(layer "F.Fab")
			(hide yes)
			(effects
				(font
					(size 1.27 1.27)
					(thickness 0.15)
				)
			)
		)
		(property "Description" "SMT Multilayer Ceramic Capacitor, 0.1 µF, 6.3 V, 0402 [1005 Metric], ± 10%, X5R, Walsin MLCC"
			(at 0 0 270)
			(layer "F.Fab")
			(hide yes)
			(effects
				(font
					(size 1.27 1.27)
					(thickness 0.15)
				)
			)
		)
		(property "Author" "Antmicro"
			(at -36.6 252.6 0)
			(layer "F.Fab")
			(hide yes)
			(effects
				(font
					(size 1 1)
					(thickness 0.15)
				)
			)
		)
		(property "Dielectric" ""
			(at -36.6 252.6 0)
			(layer "F.Fab")
			(hide yes)
			(effects
				(font
					(size 1 1)
					(thickness 0.15)
				)
			)
		)
		(property "License" "Apache-2.0"
			(at -36.6 252.6 0)
			(layer "F.Fab")
			(hide yes)
			(effects
				(font
					(size 1 1)
					(thickness 0.15)
				)
			)
		)
		(property "MPN" "0402X104K6R3CT"
			(at -36.6 252.6 0)
			(layer "F.Fab")
			(hide yes)
			(effects
				(font
					(size 1 1)
					(thickness 0.15)
				)
			)
		)
		(property "Manufacturer" "Walsin"
			(at -36.6 252.6 0)
			(layer "F.Fab")
			(hide yes)
			(effects
				(font
					(size 1 1)
					(thickness 0.15)
				)
			)
		)
		(property "Public" "False"
			(at -36.6 252.6 0)
			(layer "F.Fab")
			(hide yes)
			(effects
				(font
					(size 1 1)
					(thickness 0.15)
				)
			)
		)
		(property "Val" "100n"
			(at -36.6 252.6 0)
			(layer "F.Fab")
			(hide yes)
			(effects
				(font
					(size 1 1)
					(thickness 0.15)
				)
			)
		)
		(property "Voltage" ""
			(at -36.6 252.6 0)
			(layer "F.Fab")
			(hide yes)
			(effects
				(font
					(size 1 1)
					(thickness 0.15)
				)
			)
		)
		(sheetname "/DDR3/")
		(sheetfile "ddr3.kicad_sch")
		(attr smd)
		(fp_rect
			(start -0.925 -0.47)
			(end 0.925 0.47)
			(stroke
				(width 0.05)
				(type default)
			)
			(fill no)
			(layer "F.CrtYd")
		)
		(fp_line
			(start -0.494 0.248)
			(end -0.494 -0.25)
			(stroke
				(width 0.15)
				(type solid)
			)
			(layer "F.Fab")
		)
		(fp_line
			(start 0.504 0.248)
			(end -0.494 0.248)
			(stroke
				(width 0.15)
				(type solid)
			)
			(layer "F.Fab")
		)
		(fp_line
			(start -0.494 -0.25)
			(end 0.504 -0.25)
			(stroke
				(width 0.15)
				(type solid)
			)
			(layer "F.Fab")
		)
		(fp_line
			(start 0.504 -0.25)
			(end 0.504 0.248)
			(stroke
				(width 0.15)
				(type solid)
			)
			(layer "F.Fab")
		)
		(pad "1" smd roundrect
			(at -0.48 0 270)
			(size 0.59 0.64)
			(layers "F.Cu" "F.Mask" "F.Paste")
			(roundrect_rratio 0.25)
			(net 1 "GND")
			(pintype "passive")
		)
		(pad "2" smd roundrect
			(at 0.48 0 270)
			(size 0.59 0.64)
			(layers "F.Cu" "F.Mask" "F.Paste")
			(roundrect_rratio 0.25)
			(net 211 "DDR3_VREF")
			(pintype "passive")
		)
	)
	(footprint "antmicro-footprints:C_0402_1005Metric"
		(layer "F.Cu")
		(at 105.275 158.275 180)
		(descr "Capacitor SMD 0402")
		(tags "capacitor SMD 0402")
		(property "Reference" "C47"
			(at -2.925 -0.325 0)
			(layer "F.SilkS")
			(effects
				(font
					(size 0.7 0.7)
					(thickness 0.15)
				)
				(justify right bottom)
			)
		)
		(property "Value" "C_10u_0402"
			(at 0 1.4 0)
			(layer "F.Fab")
			(effects
				(font
					(size 0.7 0.7)
					(thickness 0.15)
				)
				(justify right bottom)
			)
		)
		(property "Datasheet" "https://www.yageo.com/en/Chart/Download/pdf/CC0402MRX5R5BB106"
			(at 0 0 180)
			(layer "F.Fab")
			(hide yes)
			(effects
				(font
					(size 1.27 1.27)
					(thickness 0.15)
				)
			)
		)
		(property "Description" "SMD Multilayer Ceramic Capacitor, 10 µF, 6.3 V, 0402 [1005 Metric], ± 20%, X5R, CC Series"
			(at 0 0 180)
			(layer "F.Fab")
			(hide yes)
			(effects
				(font
					(size 1.27 1.27)
					(thickness 0.15)
				)
			)
		)
		(property "Author" "Antmicro"
			(at 210.55 316.55 0)
			(layer "F.Fab")
			(hide yes)
			(effects
				(font
					(size 1 1)
					(thickness 0.15)
				)
			)
		)
		(property "Dielectric" ""
			(at 210.55 316.55 0)
			(layer "F.Fab")
			(hide yes)
			(effects
				(font
					(size 1 1)
					(thickness 0.15)
				)
			)
		)
		(property "License" "Apache-2.0"
			(at 210.55 316.55 0)
			(layer "F.Fab")
			(hide yes)
			(effects
				(font
					(size 1 1)
					(thickness 0.15)
				)
			)
		)
		(property "MPN" "CC0402MRX5R5BB106"
			(at 210.55 316.55 0)
			(layer "F.Fab")
			(hide yes)
			(effects
				(font
					(size 1 1)
					(thickness 0.15)
				)
			)
		)
		(property "Manufacturer" "YAGEO"
			(at 210.55 316.55 0)
			(layer "F.Fab")
			(hide yes)
			(effects
				(font
					(size 1 1)
					(thickness 0.15)
				)
			)
		)
		(property "Val" "10u"
			(at 210.55 316.55 0)
			(layer "F.Fab")
			(hide yes)
			(effects
				(font
					(size 1 1)
					(thickness 0.15)
				)
			)
		)
		(property "Voltage" ""
			(at 210.55 316.55 0)
			(layer "F.Fab")
			(hide yes)
			(effects
				(font
					(size 1 1)
					(thickness 0.15)
				)
			)
		)
		(sheetname "/DDR3/")
		(sheetfile "ddr3.kicad_sch")
		(attr smd)
		(fp_rect
			(start -0.925 -0.47)
			(end 0.925 0.47)
			(stroke
				(width 0.05)
				(type default)
			)
			(fill no)
			(layer "F.CrtYd")
		)
		(fp_line
			(start 0.504 0.248)
			(end -0.494 0.248)
			(stroke
				(width 0.15)
				(type solid)
			)
			(layer "F.Fab")
		)
		(fp_line
			(start 0.504 -0.25)
			(end 0.504 0.248)
			(stroke
				(width 0.15)
				(type solid)
			)
			(layer "F.Fab")
		)
		(fp_line
			(start -0.494 0.248)
			(end -0.494 -0.25)
			(stroke
				(width 0.15)
				(type solid)
			)
			(layer "F.Fab")
		)
		(fp_line
			(start -0.494 -0.25)
			(end 0.504 -0.25)
			(stroke
				(width 0.15)
				(type solid)
			)
			(layer "F.Fab")
		)
		(pad "1" smd roundrect
			(at -0.48 0 180)
			(size 0.59 0.64)
			(layers "F.Cu" "F.Mask" "F.Paste")
			(roundrect_rratio 0.25)
			(net 1 "GND")
			(pintype "passive")
		)
		(pad "2" smd roundrect
			(at 0.48 0 180)
			(size 0.59 0.64)
			(layers "F.Cu" "F.Mask" "F.Paste")
			(roundrect_rratio 0.25)
			(net 2 "VCC3V3")
			(pintype "passive")
		)
	)
	(footprint "antmicro-footprints:R_0402_1005Metric"
		(layer "F.Cu")
		(at 99.675 154.675 -90)
		(descr "Resistor SMD 0402")
		(tags "resistor SMD 0402")
		(property "Reference" "R57"
			(at 1.225 8.275 90)
			(layer "F.SilkS")
			(effects
				(font
					(size 0.7 0.7)
					(thickness 0.15)
				)
				(justify right bottom)
			)
		)
		(property "Value" "R_10k_0402"
			(at 0 1.4 90)
			(layer "F.Fab")
			(effects
				(font
					(size 0.7 0.7)
					(thickness 0.15)
				)
				(justify right bottom)
			)
		)
		(property "Datasheet" "https://www.bourns.com/docs/product-datasheets/cr.pdf"
			(at 0 0 270)
			(layer "F.Fab")
			(hide yes)
			(effects
				(font
					(size 1.27 1.27)
					(thickness 0.15)
				)
			)
		)
		(property "Description" "SMD Chip Resistor, 10 kohm, ± 1%, 62.5 mW, 0402 [1005 Metric], Thick Film, General Purpose"
			(at 0 0 270)
			(layer "F.Fab")
			(hide yes)
			(effects
				(font
					(size 1.27 1.27)
					(thickness 0.15)
				)
			)
		)
		(property "Author" "Antmicro"
			(at -55 254.35 0)
			(layer "F.Fab")
			(hide yes)
			(effects
				(font
					(size 1 1)
					(thickness 0.15)
				)
			)
		)
		(property "License" "Apache-2.0"
			(at -55 254.35 0)
			(layer "F.Fab")
			(hide yes)
			(effects
				(font
					(size 1 1)
					(thickness 0.15)
				)
			)
		)
		(property "MPN" "CR0402-FX-1002GLF"
			(at -55 254.35 0)
			(layer "F.Fab")
			(hide yes)
			(effects
				(font
					(size 1 1)
					(thickness 0.15)
				)
			)
		)
		(property "Manufacturer" "Bourns"
			(at -55 254.35 0)
			(layer "F.Fab")
			(hide yes)
			(effects
				(font
					(size 1 1)
					(thickness 0.15)
				)
			)
		)
		(property "Tolerance" "1%"
			(at -55 254.35 0)
			(layer "F.Fab")
			(hide yes)
			(effects
				(font
					(size 1 1)
					(thickness 0.15)
				)
			)
		)
		(property "Val" "10k"
			(at -55 254.35 0)
			(layer "F.Fab")
			(hide yes)
			(effects
				(font
					(size 1 1)
					(thickness 0.15)
				)
			)
		)
		(sheetname "/DDR3/")
		(sheetfile "ddr3.kicad_sch")
		(attr smd)
		(fp_rect
			(start -0.925 -0.47)
			(end 0.925 0.47)
			(stroke
				(width 0.05)
				(type default)
			)
			(fill no)
			(layer "F.CrtYd")
		)
		(fp_rect
			(start -0.5 -0.25)
			(end 0.5 0.25)
			(stroke
				(width 0.15)
				(type solid)
			)
			(fill no)
			(layer "F.Fab")
		)
		(pad "1" smd roundrect
			(at -0.48 0 270)
			(size 0.59 0.64)
			(layers "F.Cu" "F.Mask" "F.Paste")
			(roundrect_rratio 0.25)
			(net 1 "GND")
			(pintype "passive")
		)
		(pad "2" smd roundrect
			(at 0.48 0 270)
			(size 0.59 0.64)
			(layers "F.Cu" "F.Mask" "F.Paste")
			(roundrect_rratio 0.25)
			(net 9 "Net-(U8-REFIN)")
			(pintype "passive")
		)
	)
	(footprint "antmicro-footprints:R_0402_1005Metric"
		(layer "F.Cu")
		(at 100.675 154.675 -90)
		(descr "Resistor SMD 0402")
		(tags "resistor SMD 0402")
		(property "Reference" "R58"
			(at 1.225 8.175 90)
			(layer "F.SilkS")
			(effects
				(font
					(size 0.7 0.7)
					(thickness 0.15)
				)
				(justify right bottom)
			)
		)
		(property "Value" "R_10k_0402"
			(at 0 1.4 90)
			(layer "F.Fab")
			(effects
				(font
					(size 0.7 0.7)
					(thickness 0.15)
				)
				(justify right bottom)
			)
		)
		(property "Datasheet" "https://www.bourns.com/docs/product-datasheets/cr.pdf"
			(at 0 0 270)
			(layer "F.Fab")
			(hide yes)
			(effects
				(font
					(size 1.27 1.27)
					(thickness 0.15)
				)
			)
		)
		(property "Description" "SMD Chip Resistor, 10 kohm, ± 1%, 62.5 mW, 0402 [1005 Metric], Thick Film, General Purpose"
			(at 0 0 270)
			(layer "F.Fab")
			(hide yes)
			(effects
				(font
					(size 1.27 1.27)
					(thickness 0.15)
				)
			)
		)
		(property "Author" "Antmicro"
			(at -54 255.35 0)
			(layer "F.Fab")
			(hide yes)
			(effects
				(font
					(size 1 1)
					(thickness 0.15)
				)
			)
		)
		(property "License" "Apache-2.0"
			(at -54 255.35 0)
			(layer "F.Fab")
			(hide yes)
			(effects
				(font
					(size 1 1)
					(thickness 0.15)
				)
			)
		)
		(property "MPN" "CR0402-FX-1002GLF"
			(at -54 255.35 0)
			(layer "F.Fab")
			(hide yes)
			(effects
				(font
					(size 1 1)
					(thickness 0.15)
				)
			)
		)
		(property "Manufacturer" "Bourns"
			(at -54 255.35 0)
			(layer "F.Fab")
			(hide yes)
			(effects
				(font
					(size 1 1)
					(thickness 0.15)
				)
			)
		)
		(property "Tolerance" "1%"
			(at -54 255.35 0)
			(layer "F.Fab")
			(hide yes)
			(effects
				(font
					(size 1 1)
					(thickness 0.15)
				)
			)
		)
		(property "Val" "10k"
			(at -54 255.35 0)
			(layer "F.Fab")
			(hide yes)
			(effects
				(font
					(size 1 1)
					(thickness 0.15)
				)
			)
		)
		(sheetname "/DDR3/")
		(sheetfile "ddr3.kicad_sch")
		(attr smd)
		(fp_rect
			(start -0.925 -0.47)
			(end 0.925 0.47)
			(stroke
				(width 0.05)
				(type default)
			)
			(fill no)
			(layer "F.CrtYd")
		)
		(fp_rect
			(start -0.5 -0.25)
			(end 0.5 0.25)
			(stroke
				(width 0.15)
				(type solid)
			)
			(fill no)
			(layer "F.Fab")
		)
		(pad "1" smd roundrect
			(at -0.48 0 270)
			(size 0.59 0.64)
			(layers "F.Cu" "F.Mask" "F.Paste")
			(roundrect_rratio 0.25)
			(net 3 "VCC1V35")
			(pintype "passive")
		)
		(pad "2" smd roundrect
			(at 0.48 0 270)
			(size 0.59 0.64)
			(layers "F.Cu" "F.Mask" "F.Paste")
			(roundrect_rratio 0.25)
			(net 9 "Net-(U8-REFIN)")
			(pintype "passive")
		)
	)
	(footprint "antmicro-footprints:R_0402_1005Metric"
		(layer "F.Cu")
		(at 105.275 159.275 180)
		(descr "Resistor SMD 0402")
		(tags "resistor SMD 0402")
		(property "Reference" "R59"
			(at -2.926 -0.325 0)
			(layer "F.SilkS")
			(effects
				(font
					(size 0.7 0.7)
					(thickness 0.15)
				)
				(justify right bottom)
			)
		)
		(property "Value" "R_10k_0402"
			(at 0 1.4 0)
			(layer "F.Fab")
			(effects
				(font
					(size 0.7 0.7)
					(thickness 0.15)
				)
				(justify right bottom)
			)
		)
		(property "Datasheet" "https://www.bourns.com/docs/product-datasheets/cr.pdf"
			(at 0 0 180)
			(layer "F.Fab")
			(hide yes)
			(effects
				(font
					(size 1.27 1.27)
					(thickness 0.15)
				)
			)
		)
		(property "Description" "SMD Chip Resistor, 10 kohm, ± 1%, 62.5 mW, 0402 [1005 Metric], Thick Film, General Purpose"
			(at 0 0 180)
			(layer "F.Fab")
			(hide yes)
			(effects
				(font
					(size 1.27 1.27)
					(thickness 0.15)
				)
			)
		)
		(property "Author" "Antmicro"
			(at 210.55 318.55 0)
			(layer "F.Fab")
			(hide yes)
			(effects
				(font
					(size 1 1)
					(thickness 0.15)
				)
			)
		)
		(property "License" "Apache-2.0"
			(at 210.55 318.55 0)
			(layer "F.Fab")
			(hide yes)
			(effects
				(font
					(size 1 1)
					(thickness 0.15)
				)
			)
		)
		(property "MPN" "CR0402-FX-1002GLF"
			(at 210.55 318.55 0)
			(layer "F.Fab")
			(hide yes)
			(effects
				(font
					(size 1 1)
					(thickness 0.15)
				)
			)
		)
		(property "Manufacturer" "Bourns"
			(at 210.55 318.55 0)
			(layer "F.Fab")
			(hide yes)
			(effects
				(font
					(size 1 1)
					(thickness 0.15)
				)
			)
		)
		(property "Tolerance" "1%"
			(at 210.55 318.55 0)
			(layer "F.Fab")
			(hide yes)
			(effects
				(font
					(size 1 1)
					(thickness 0.15)
				)
			)
		)
		(property "Val" "10k"
			(at 210.55 318.55 0)
			(layer "F.Fab")
			(hide yes)
			(effects
				(font
					(size 1 1)
					(thickness 0.15)
				)
			)
		)
		(sheetname "/DDR3/")
		(sheetfile "ddr3.kicad_sch")
		(attr smd)
		(fp_rect
			(start -0.925 -0.47)
			(end 0.925 0.47)
			(stroke
				(width 0.05)
				(type default)
			)
			(fill no)
			(layer "F.CrtYd")
		)
		(fp_rect
			(start -0.5 -0.25)
			(end 0.5 0.25)
			(stroke
				(width 0.15)
				(type solid)
			)
			(fill no)
			(layer "F.Fab")
		)
		(pad "1" smd roundrect
			(at -0.48 0 180)
			(size 0.59 0.64)
			(layers "F.Cu" "F.Mask" "F.Paste")
			(roundrect_rratio 0.25)
			(net 2 "VCC3V3")
			(pintype "passive")
		)
		(pad "2" smd roundrect
			(at 0.48 0 180)
			(size 0.59 0.64)
			(layers "F.Cu" "F.Mask" "F.Paste")
			(roundrect_rratio 0.25)
			(net 334 "Net-(U8-PGOOD)")
			(pintype "passive")
		)
	)
)
